(kicad_pcb
	(version 20260206)
	(generator "pcbnew")
	(generator_version "10.0")
	(general
		(thickness 1.6)
		(legacy_teardrops no)
	)
	(paper "A4")
	(title_block
		(title "04192023_DAF0TMB3IC0_F0TG_MB_C_brd_V02_OCP.brd")
		(comment 1 "Grand Teton / footprints 496-502 of 8354")
	)
	(layers
		(0 "F.Cu" signal "TOP")
		(4 "In1.Cu" signal "GND")
		(6 "In2.Cu" signal "IN1")
		(8 "In3.Cu" signal "GND1")
		(10 "In4.Cu" signal "IN2")
		(12 "In5.Cu" signal "GND2")
		(14 "In6.Cu" signal "IN3")
		(16 "In7.Cu" signal "GND3")
		(18 "In8.Cu" signal "VCC")
		(20 "In9.Cu" signal "VCC1")
		(22 "In10.Cu" signal "GND4")
		(24 "In11.Cu" signal "IN4")
		(26 "In12.Cu" signal "GND5")
		(28 "In13.Cu" signal "IN5")
		(30 "In14.Cu" signal "GND6")
		(32 "In15.Cu" signal "IN6")
		(34 "In16.Cu" signal "GND7")
		(2 "B.Cu" signal "BOTTOM")
		(9 "F.Adhes" user "F.Adhesive")
		(11 "B.Adhes" user "B.Adhesive")
		(13 "F.Paste" user "Package Geometry/Pastemask Top")
		(15 "B.Paste" user "Package Geometry/Pastemask Bottom")
		(5 "F.SilkS" user "Ref Des/Silkscreen Top")
		(7 "B.SilkS" user "Ref Des/Silkscreen Bottom")
		(1 "F.Mask" user "Board Geometry/Soldermask Top")
		(3 "B.Mask" user "Board Geometry/Soldermask Bottom")
		(17 "Dwgs.User" user "User.Drawings")
		(19 "Cmts.User" user "User.Comments")
		(21 "Eco1.User" user "User.Eco1")
		(23 "Eco2.User" user "User.Eco2")
		(25 "Edge.Cuts" user "Board Geometry/Outline")
		(27 "Margin" user)
		(31 "F.CrtYd" user "Package Geometry/Place Bound Top")
		(29 "B.CrtYd" user "Package Geometry/Place Bound Bottom")
		(35 "F.Fab" user "Ref Des/Assembly Top")
		(33 "B.Fab" user "Ref Des/Assembly Bottom")
	)
	(footprint ""
		(layer "F.Cu")
		(at 59.169808 -71.527416)
		(property "Reference" "ME3"
			(at 0 0 0)
			(layer "F.SilkS")
			(hide yes)
			(effects
				(font
					(size 1.27 1.27)
				)
			)
		)
		(property "Value" ""
			(at 0 0 0)
			(layer "F.Fab")
			(effects
				(font
					(size 1.27 1.27)
				)
			)
		)
		(duplicate_pad_numbers_are_jumpers no)
	)
	(footprint ""
		(layer "F.Cu")
		(at 110.525814 -256.012442 90)
		(property "Reference" "C2475"
			(at 0 0 90)
			(layer "F.SilkS")
			(hide yes)
			(effects
				(font
					(size 1.27 1.27)
				)
			)
		)
		(property "Value" ""
			(at 0 0 90)
			(layer "F.Fab")
			(effects
				(font
					(size 1.27 1.27)
				)
			)
		)
		(duplicate_pad_numbers_are_jumpers no)
		(fp_line
			(start 0.7874 -0.4064)
			(end 0.7874 0.4064)
			(stroke
				(width 0.1524)
				(type default)
			)
			(layer "F.SilkS")
		)
		(fp_line
			(start -0.7874 -0.4064)
			(end 0.7874 -0.4064)
			(stroke
				(width 0.1524)
				(type default)
			)
			(layer "F.SilkS")
		)
		(fp_line
			(start 0.7874 0.4064)
			(end -0.7874 0.4064)
			(stroke
				(width 0.1524)
				(type default)
			)
			(layer "F.SilkS")
		)
		(fp_line
			(start -0.7874 0.4064)
			(end -0.7874 -0.4064)
			(stroke
				(width 0.1524)
				(type default)
			)
			(layer "F.SilkS")
		)
		(fp_line
			(start -0.12065 -0.305054)
			(end -0.12065 -0.2794)
			(stroke
				(width 0.1)
				(type default)
			)
			(layer "F.Fab")
		)
		(fp_line
			(start -0.67945 -0.305054)
			(end -0.12065 -0.305054)
			(stroke
				(width 0.1)
				(type default)
			)
			(layer "F.Fab")
		)
		(fp_line
			(start 0.67945 -0.3048)
			(end 0.67945 0.3048)
			(stroke
				(width 0.1)
				(type default)
			)
			(layer "F.Fab")
		)
		(fp_line
			(start 0.12065 -0.3048)
			(end 0.67945 -0.3048)
			(stroke
				(width 0.1)
				(type default)
			)
			(layer "F.Fab")
		)
		(fp_line
			(start 0.12065 -0.2794)
			(end 0.12065 -0.3048)
			(stroke
				(width 0.1)
				(type default)
			)
			(layer "F.Fab")
		)
		(fp_line
			(start -0.12065 -0.2794)
			(end 0.12065 -0.2794)
			(stroke
				(width 0.1)
				(type default)
			)
			(layer "F.Fab")
		)
		(fp_line
			(start 0.120396 0.2794)
			(end -0.12065 0.2794)
			(stroke
				(width 0.1)
				(type default)
			)
			(layer "F.Fab")
		)
		(fp_line
			(start -0.12065 0.2794)
			(end -0.12065 0.3048)
			(stroke
				(width 0.1)
				(type default)
			)
			(layer "F.Fab")
		)
		(fp_line
			(start 0.67945 0.3048)
			(end 0.120396 0.3048)
			(stroke
				(width 0.1)
				(type default)
			)
			(layer "F.Fab")
		)
		(fp_line
			(start 0.120396 0.3048)
			(end 0.120396 0.2794)
			(stroke
				(width 0.1)
				(type default)
			)
			(layer "F.Fab")
		)
		(fp_line
			(start -0.12065 0.3048)
			(end -0.67945 0.3048)
			(stroke
				(width 0.1)
				(type default)
			)
			(layer "F.Fab")
		)
		(fp_line
			(start -0.67945 0.3048)
			(end -0.67945 -0.305054)
			(stroke
				(width 0.1)
				(type default)
			)
			(layer "F.Fab")
		)
		(pad "1" smd circle
			(at -0.40005 0 90)
			(size 0 0)
			(layers "F.Cu" "F.Mask" "F.Paste")
			(net "PVDDCR_SOC_P1")
		)
		(pad "2" smd circle
			(at 0.40005 0 90)
			(size 0 0)
			(layers "F.Cu" "F.Mask" "F.Paste")
			(net "GND")
		)
	)
	(footprint ""
		(layer "F.Cu")
		(at 359.059988 -416.392868 90)
		(property "Reference" "C1803"
			(at 0 0 90)
			(layer "F.SilkS")
			(hide yes)
			(effects
				(font
					(size 1.27 1.27)
				)
			)
		)
		(property "Value" ""
			(at 0 0 90)
			(layer "F.Fab")
			(effects
				(font
					(size 1.27 1.27)
				)
			)
		)
		(duplicate_pad_numbers_are_jumpers no)
		(fp_line
			(start 0.7874 -0.4064)
			(end 0.7874 0.4064)
			(stroke
				(width 0.1524)
				(type default)
			)
			(layer "F.SilkS")
		)
		(fp_line
			(start -0.7874 -0.4064)
			(end 0.7874 -0.4064)
			(stroke
				(width 0.1524)
				(type default)
			)
			(layer "F.SilkS")
		)
		(fp_line
			(start 0.7874 0.4064)
			(end -0.7874 0.4064)
			(stroke
				(width 0.1524)
				(type default)
			)
			(layer "F.SilkS")
		)
		(fp_line
			(start -0.7874 0.4064)
			(end -0.7874 -0.4064)
			(stroke
				(width 0.1524)
				(type default)
			)
			(layer "F.SilkS")
		)
		(fp_line
			(start -0.12065 -0.305054)
			(end -0.12065 -0.2794)
			(stroke
				(width 0.1)
				(type default)
			)
			(layer "F.Fab")
		)
		(fp_line
			(start -0.67945 -0.305054)
			(end -0.12065 -0.305054)
			(stroke
				(width 0.1)
				(type default)
			)
			(layer "F.Fab")
		)
		(fp_line
			(start 0.67945 -0.3048)
			(end 0.67945 0.3048)
			(stroke
				(width 0.1)
				(type default)
			)
			(layer "F.Fab")
		)
		(fp_line
			(start 0.12065 -0.3048)
			(end 0.67945 -0.3048)
			(stroke
				(width 0.1)
				(type default)
			)
			(layer "F.Fab")
		)
		(fp_line
			(start 0.12065 -0.2794)
			(end 0.12065 -0.3048)
			(stroke
				(width 0.1)
				(type default)
			)
			(layer "F.Fab")
		)
		(fp_line
			(start -0.12065 -0.2794)
			(end 0.12065 -0.2794)
			(stroke
				(width 0.1)
				(type default)
			)
			(layer "F.Fab")
		)
		(fp_line
			(start 0.120396 0.2794)
			(end -0.12065 0.2794)
			(stroke
				(width 0.1)
				(type default)
			)
			(layer "F.Fab")
		)
		(fp_line
			(start -0.12065 0.2794)
			(end -0.12065 0.3048)
			(stroke
				(width 0.1)
				(type default)
			)
			(layer "F.Fab")
		)
		(fp_line
			(start 0.67945 0.3048)
			(end 0.120396 0.3048)
			(stroke
				(width 0.1)
				(type default)
			)
			(layer "F.Fab")
		)
		(fp_line
			(start 0.120396 0.3048)
			(end 0.120396 0.2794)
			(stroke
				(width 0.1)
				(type default)
			)
			(layer "F.Fab")
		)
		(fp_line
			(start -0.12065 0.3048)
			(end -0.67945 0.3048)
			(stroke
				(width 0.1)
				(type default)
			)
			(layer "F.Fab")
		)
		(fp_line
			(start -0.67945 0.3048)
			(end -0.67945 -0.305054)
			(stroke
				(width 0.1)
				(type default)
			)
			(layer "F.Fab")
		)
		(pad "1" smd circle
			(at -0.40005 0 90)
			(size 0 0)
			(layers "F.Cu" "F.Mask" "F.Paste")
			(net "P3V3_AUX")
		)
		(pad "2" smd circle
			(at 0.40005 0 90)
			(size 0 0)
			(layers "F.Cu" "F.Mask" "F.Paste")
			(net "GND")
		)
	)
	(footprint ""
		(layer "F.Cu")
		(at 200.952608 -111.593376)
		(property "Reference" "C5001"
			(at 0 0 0)
			(layer "F.SilkS")
			(hide yes)
			(effects
				(font
					(size 1.27 1.27)
				)
			)
		)
		(property "Value" ""
			(at 0 0 0)
			(layer "F.Fab")
			(effects
				(font
					(size 1.27 1.27)
				)
			)
		)
		(duplicate_pad_numbers_are_jumpers no)
		(fp_line
			(start -0.7874 -0.4064)
			(end 0.7874 -0.4064)
			(stroke
				(width 0.1524)
				(type default)
			)
			(layer "F.SilkS")
		)
		(fp_line
			(start -0.7874 0.4064)
			(end -0.7874 -0.4064)
			(stroke
				(width 0.1524)
				(type default)
			)
			(layer "F.SilkS")
		)
		(fp_line
			(start 0.7874 -0.4064)
			(end 0.7874 0.4064)
			(stroke
				(width 0.1524)
				(type default)
			)
			(layer "F.SilkS")
		)
		(fp_line
			(start 0.7874 0.4064)
			(end -0.7874 0.4064)
			(stroke
				(width 0.1524)
				(type default)
			)
			(layer "F.SilkS")
		)
		(fp_line
			(start -0.67945 -0.305054)
			(end -0.12065 -0.305054)
			(stroke
				(width 0.1)
				(type default)
			)
			(layer "F.Fab")
		)
		(fp_line
			(start -0.67945 0.3048)
			(end -0.67945 -0.305054)
			(stroke
				(width 0.1)
				(type default)
			)
			(layer "F.Fab")
		)
		(fp_line
			(start -0.12065 -0.305054)
			(end -0.12065 -0.2794)
			(stroke
				(width 0.1)
				(type default)
			)
			(layer "F.Fab")
		)
		(fp_line
			(start -0.12065 -0.2794)
			(end 0.12065 -0.2794)
			(stroke
				(width 0.1)
				(type default)
			)
			(layer "F.Fab")
		)
		(fp_line
			(start -0.12065 0.2794)
			(end -0.12065 0.3048)
			(stroke
				(width 0.1)
				(type default)
			)
			(layer "F.Fab")
		)
		(fp_line
			(start -0.12065 0.3048)
			(end -0.67945 0.3048)
			(stroke
				(width 0.1)
				(type default)
			)
			(layer "F.Fab")
		)
		(fp_line
			(start 0.120396 0.2794)
			(end -0.12065 0.2794)
			(stroke
				(width 0.1)
				(type default)
			)
			(layer "F.Fab")
		)
		(fp_line
			(start 0.120396 0.3048)
			(end 0.120396 0.2794)
			(stroke
				(width 0.1)
				(type default)
			)
			(layer "F.Fab")
		)
		(fp_line
			(start 0.12065 -0.3048)
			(end 0.67945 -0.3048)
			(stroke
				(width 0.1)
				(type default)
			)
			(layer "F.Fab")
		)
		(fp_line
			(start 0.12065 -0.2794)
			(end 0.12065 -0.3048)
			(stroke
				(width 0.1)
				(type default)
			)
			(layer "F.Fab")
		)
		(fp_line
			(start 0.67945 -0.3048)
			(end 0.67945 0.3048)
			(stroke
				(width 0.1)
				(type default)
			)
			(layer "F.Fab")
		)
		(fp_line
			(start 0.67945 0.3048)
			(end 0.120396 0.3048)
			(stroke
				(width 0.1)
				(type default)
			)
			(layer "F.Fab")
		)
		(pad "1" smd circle
			(at -0.40005 0)
			(size 0 0)
			(layers "F.Cu" "F.Mask" "F.Paste")
			(net "FM_PWRGD_PVDD18_S5_P0")
		)
		(pad "2" smd circle
			(at 0.40005 0)
			(size 0 0)
			(layers "F.Cu" "F.Mask" "F.Paste")
			(net "GND")
		)
	)
	(footprint ""
		(layer "F.Cu")
		(at 191.135 -129.377948 90)
		(property "Reference" "R1359"
			(at 0 0 90)
			(layer "F.SilkS")
			(hide yes)
			(effects
				(font
					(size 1.27 1.27)
				)
			)
		)
		(property "Value" ""
			(at 0 0 90)
			(layer "F.Fab")
			(effects
				(font
					(size 1.27 1.27)
				)
			)
		)
		(duplicate_pad_numbers_are_jumpers no)
		(fp_line
			(start 0.7874 -0.4064)
			(end 0.7874 0.4064)
			(stroke
				(width 0.1524)
				(type default)
			)
			(layer "F.SilkS")
		)
		(fp_line
			(start -0.7874 -0.4064)
			(end 0.7874 -0.4064)
			(stroke
				(width 0.1524)
				(type default)
			)
			(layer "F.SilkS")
		)
		(fp_line
			(start 0.7874 0.4064)
			(end -0.7874 0.4064)
			(stroke
				(width 0.1524)
				(type default)
			)
			(layer "F.SilkS")
		)
		(fp_line
			(start -0.7874 0.4064)
			(end -0.7874 -0.4064)
			(stroke
				(width 0.1524)
				(type default)
			)
			(layer "F.SilkS")
		)
		(fp_line
			(start -0.12065 -0.305054)
			(end -0.12065 -0.2794)
			(stroke
				(width 0.1)
				(type default)
			)
			(layer "F.Fab")
		)
		(fp_line
			(start -0.67945 -0.305054)
			(end -0.12065 -0.305054)
			(stroke
				(width 0.1)
				(type default)
			)
			(layer "F.Fab")
		)
		(fp_line
			(start 0.67945 -0.3048)
			(end 0.67945 0.3048)
			(stroke
				(width 0.1)
				(type default)
			)
			(layer "F.Fab")
		)
		(fp_line
			(start 0.12065 -0.3048)
			(end 0.67945 -0.3048)
			(stroke
				(width 0.1)
				(type default)
			)
			(layer "F.Fab")
		)
		(fp_line
			(start 0.12065 -0.2794)
			(end 0.12065 -0.3048)
			(stroke
				(width 0.1)
				(type default)
			)
			(layer "F.Fab")
		)
		(fp_line
			(start -0.12065 -0.2794)
			(end 0.12065 -0.2794)
			(stroke
				(width 0.1)
				(type default)
			)
			(layer "F.Fab")
		)
		(fp_line
			(start 0.120396 0.2794)
			(end -0.12065 0.2794)
			(stroke
				(width 0.1)
				(type default)
			)
			(layer "F.Fab")
		)
		(fp_line
			(start -0.12065 0.2794)
			(end -0.12065 0.3048)
			(stroke
				(width 0.1)
				(type default)
			)
			(layer "F.Fab")
		)
		(fp_line
			(start 0.67945 0.3048)
			(end 0.120396 0.3048)
			(stroke
				(width 0.1)
				(type default)
			)
			(layer "F.Fab")
		)
		(fp_line
			(start 0.120396 0.3048)
			(end 0.120396 0.2794)
			(stroke
				(width 0.1)
				(type default)
			)
			(layer "F.Fab")
		)
		(fp_line
			(start -0.12065 0.3048)
			(end -0.67945 0.3048)
			(stroke
				(width 0.1)
				(type default)
			)
			(layer "F.Fab")
		)
		(fp_line
			(start -0.67945 0.3048)
			(end -0.67945 -0.305054)
			(stroke
				(width 0.1)
				(type default)
			)
			(layer "F.Fab")
		)
		(pad "1" smd circle
			(at -0.40005 0 90)
			(size 0 0)
			(layers "F.Cu" "F.Mask" "F.Paste")
			(net "BMC_JTAG_SEL_R")
		)
		(pad "2" smd circle
			(at 0.40005 0 90)
			(size 0 0)
			(layers "F.Cu" "F.Mask" "F.Paste")
			(net "BMC_JTAG_SEL")
		)
	)
	(footprint ""
		(layer "F.Cu")
		(at 287.570672 -412.74111 -90)
		(property "Reference" "R4520"
			(at 0 0 270)
			(layer "F.SilkS")
			(hide yes)
			(effects
				(font
					(size 1.27 1.27)
				)
			)
		)
		(property "Value" ""
			(at 0 0 270)
			(layer "F.Fab")
			(effects
				(font
					(size 1.27 1.27)
				)
			)
		)
		(duplicate_pad_numbers_are_jumpers no)
		(fp_line
			(start -0.7874 0.4064)
			(end -0.7874 -0.4064)
			(stroke
				(width 0.1524)
				(type default)
			)
			(layer "F.SilkS")
		)
		(fp_line
			(start 0.7874 0.4064)
			(end -0.7874 0.4064)
			(stroke
				(width 0.1524)
				(type default)
			)
			(layer "F.SilkS")
		)
		(fp_line
			(start -0.7874 -0.4064)
			(end 0.7874 -0.4064)
			(stroke
				(width 0.1524)
				(type default)
			)
			(layer "F.SilkS")
		)
		(fp_line
			(start 0.7874 -0.4064)
			(end 0.7874 0.4064)
			(stroke
				(width 0.1524)
				(type default)
			)
			(layer "F.SilkS")
		)
		(fp_line
			(start -0.67945 0.3048)
			(end -0.67945 -0.305054)
			(stroke
				(width 0.1)
				(type default)
			)
			(layer "F.Fab")
		)
		(fp_line
			(start -0.12065 0.3048)
			(end -0.67945 0.3048)
			(stroke
				(width 0.1)
				(type default)
			)
			(layer "F.Fab")
		)
		(fp_line
			(start 0.120396 0.3048)
			(end 0.120396 0.2794)
			(stroke
				(width 0.1)
				(type default)
			)
			(layer "F.Fab")
		)
		(fp_line
			(start 0.67945 0.3048)
			(end 0.120396 0.3048)
			(stroke
				(width 0.1)
				(type default)
			)
			(layer "F.Fab")
		)
		(fp_line
			(start -0.12065 0.2794)
			(end -0.12065 0.3048)
			(stroke
				(width 0.1)
				(type default)
			)
			(layer "F.Fab")
		)
		(fp_line
			(start 0.120396 0.2794)
			(end -0.12065 0.2794)
			(stroke
				(width 0.1)
				(type default)
			)
			(layer "F.Fab")
		)
		(fp_line
			(start -0.12065 -0.2794)
			(end 0.12065 -0.2794)
			(stroke
				(width 0.1)
				(type default)
			)
			(layer "F.Fab")
		)
		(fp_line
			(start 0.12065 -0.2794)
			(end 0.12065 -0.3048)
			(stroke
				(width 0.1)
				(type default)
			)
			(layer "F.Fab")
		)
		(fp_line
			(start 0.12065 -0.3048)
			(end 0.67945 -0.3048)
			(stroke
				(width 0.1)
				(type default)
			)
			(layer "F.Fab")
		)
		(fp_line
			(start 0.67945 -0.3048)
			(end 0.67945 0.3048)
			(stroke
				(width 0.1)
				(type default)
			)
			(layer "F.Fab")
		)
		(fp_line
			(start -0.67945 -0.305054)
			(end -0.12065 -0.305054)
			(stroke
				(width 0.1)
				(type default)
			)
			(layer "F.Fab")
		)
		(fp_line
			(start -0.12065 -0.305054)
			(end -0.12065 -0.2794)
			(stroke
				(width 0.1)
				(type default)
			)
			(layer "F.Fab")
		)
		(pad "1" smd circle
			(at -0.40005 0 270)
			(size 0 0)
			(layers "F.Cu" "F.Mask" "F.Paste")
			(net "FM_9ZXL045_P0_0_OE_N")
		)
		(pad "2" smd circle
			(at 0.40005 0 270)
			(size 0 0)
			(layers "F.Cu" "F.Mask" "F.Paste")
			(net "GND")
		)
	)
	(footprint ""
		(layer "F.Cu")
		(at 378.916692 -383.88163 -90)
		(property "Reference" "C886"
			(at 0 0 270)
			(layer "F.SilkS")
			(hide yes)
			(effects
				(font
					(size 1.27 1.27)
				)
			)
		)
		(property "Value" ""
			(at 0 0 270)
			(layer "F.Fab")
			(effects
				(font
					(size 1.27 1.27)
				)
			)
		)
		(duplicate_pad_numbers_are_jumpers no)
		(fp_line
			(start -0.299974 0.150114)
			(end -0.299974 -0.150114)
			(stroke
				(width 0.1)
				(type default)
			)
			(layer "F.Fab")
		)
		(fp_line
			(start 0.299974 0.150114)
			(end -0.299974 0.150114)
			(stroke
				(width 0.1)
				(type default)
			)
			(layer "F.Fab")
		)
		(fp_line
			(start -0.299974 -0.150114)
			(end 0.299974 -0.150114)
			(stroke
				(width 0.1)
				(type default)
			)
			(layer "F.Fab")
		)
		(fp_line
			(start 0.299974 -0.150114)
			(end 0.299974 0.150114)
			(stroke
				(width 0.1)
				(type default)
			)
			(layer "F.Fab")
		)
		(pad "1" smd rect
			(at -0.2667 0 270)
			(size 0.3048 0.381)
			(layers "F.Cu" "F.Mask" "F.Paste")
			(net "P5E_CPU0_P3_TX_C_DN<7>")
		)
		(pad "2" smd rect
			(at 0.2667 0 270)
			(size 0.3048 0.381)
			(layers "F.Cu" "F.Mask" "F.Paste")
			(net "P5E_CPU0_P3_TX_DN<7>")
		)
	)
)
